(kicad_pcb
	(version 20260206)
	(generator "pcbnew")
	(generator_version "10.0")
	(general
		(thickness 1.6)
		(legacy_teardrops no)
	)
	(paper "A4")
	(title_block
		(title "01162023_DA0F0TEBIF0_F0T_Expander_BD_F_brd_V02_OCP.brd")
		(comment 1 "Grand Teton / footprints 6909-6915 of 9728")
	)
	(layers
		(0 "F.Cu" signal "TOP")
		(4 "In1.Cu" signal "GND")
		(6 "In2.Cu" signal "VCC")
		(8 "In3.Cu" signal "VCC1")
		(10 "In4.Cu" signal "GND1")
		(12 "In5.Cu" signal "IN1")
		(14 "In6.Cu" signal "GND2")
		(16 "In7.Cu" signal "IN2")
		(18 "In8.Cu" signal "GND3")
		(20 "In9.Cu" signal "IN3")
		(22 "In10.Cu" signal "GND4")
		(24 "In11.Cu" signal "IN4")
		(26 "In12.Cu" signal "GND5")
		(28 "In13.Cu" signal "IN5")
		(30 "In14.Cu" signal "GND6")
		(32 "In15.Cu" signal "IN6")
		(34 "In16.Cu" signal "GND7")
		(2 "B.Cu" signal "BOTTOM")
		(9 "F.Adhes" user "F.Adhesive")
		(11 "B.Adhes" user "B.Adhesive")
		(13 "F.Paste" user "Package Geometry/Pastemask Top")
		(15 "B.Paste" user "Package Geometry/Pastemask Bottom")
		(5 "F.SilkS" user "Ref Des/Silkscreen Top")
		(7 "B.SilkS" user "Ref Des/Silkscreen Bottom")
		(1 "F.Mask" user "Board Geometry/Soldermask Top")
		(3 "B.Mask" user "Board Geometry/Soldermask Bottom")
		(17 "Dwgs.User" user "User.Drawings")
		(19 "Cmts.User" user "User.Comments")
		(21 "Eco1.User" user "User.Eco1")
		(23 "Eco2.User" user "User.Eco2")
		(25 "Edge.Cuts" user "Board Geometry/Outline")
		(27 "Margin" user)
		(31 "F.CrtYd" user "Package Geometry/Place Bound Top")
		(29 "B.CrtYd" user "Package Geometry/Place Bound Bottom")
		(35 "F.Fab" user "Ref Des/Assembly Top")
		(33 "B.Fab" user "Ref Des/Assembly Bottom")
	)
	(footprint ""
		(layer "F.Cu")
		(at 222.011494 -181.14518)
		(property "Reference" "Q58"
			(at -0.472694 1.82245 0)
			(unlocked yes)
			(layer "F.SilkS")
			(effects
				(font
					(size 0.7874 0.5842)
					(thickness 0.1524)
				)
				(justify left)
			)
		)
		(property "Value" ""
			(at 0 0 0)
			(layer "F.Fab")
			(effects
				(font
					(size 1.27 1.27)
				)
			)
		)
		(duplicate_pad_numbers_are_jumpers no)
		(fp_line
			(start -1.38176 -1.100074)
			(end -1.38176 1.100074)
			(stroke
				(width 0.1524)
				(type default)
			)
			(layer "F.SilkS")
		)
		(fp_line
			(start -1.38176 1.100074)
			(end 1.38176 1.100074)
			(stroke
				(width 0.1524)
				(type default)
			)
			(layer "F.SilkS")
		)
		(fp_line
			(start -0.592074 -1.100074)
			(end -1.38176 -1.100074)
			(stroke
				(width 0.1524)
				(type default)
			)
			(layer "F.SilkS")
		)
		(fp_line
			(start 0 -0.508)
			(end -0.592074 -1.100074)
			(stroke
				(width 0.1524)
				(type default)
			)
			(layer "F.SilkS")
		)
		(fp_line
			(start 0.592074 -1.100074)
			(end 0 -0.508)
			(stroke
				(width 0.1524)
				(type default)
			)
			(layer "F.SilkS")
		)
		(fp_line
			(start 1.38176 -1.100074)
			(end 0.592074 -1.100074)
			(stroke
				(width 0.1524)
				(type default)
			)
			(layer "F.SilkS")
		)
		(fp_line
			(start 1.38176 1.100074)
			(end 1.38176 -1.100074)
			(stroke
				(width 0.1524)
				(type default)
			)
			(layer "F.SilkS")
		)
		(fp_poly
			(pts
				(xy -1.9431 -0.870204) (xy -1.50241 -0.649986) (xy -1.9431 -0.429768)
			)
			(stroke
				(width 0)
				(type default)
			)
			(fill yes)
			(layer "F.SilkS")
		)
		(fp_line
			(start -0.674878 -1.100074)
			(end -0.674878 1.100074)
			(stroke
				(width 0.1)
				(type default)
			)
			(layer "F.Fab")
		)
		(fp_line
			(start -0.674878 1.100074)
			(end 0.674878 1.100074)
			(stroke
				(width 0.1)
				(type default)
			)
			(layer "F.Fab")
		)
		(fp_line
			(start 0.674878 -1.100074)
			(end -0.674878 -1.100074)
			(stroke
				(width 0.1)
				(type default)
			)
			(layer "F.Fab")
		)
		(fp_line
			(start 0.674878 1.100074)
			(end 0.674878 -1.100074)
			(stroke
				(width 0.1)
				(type default)
			)
			(layer "F.Fab")
		)
		(fp_poly
			(pts
				(xy -1.9431 -0.870204) (xy -1.50241 -0.649986) (xy -1.9431 -0.429768)
			)
			(stroke
				(width 0)
				(type default)
			)
			(fill yes)
			(layer "F.Fab")
		)
		(pad "1" smd rect
			(at -0.94996 -0.649986 270)
			(size 0.4318 0.6096)
			(layers "F.Cu" "F.Mask" "F.Paste")
			(net "GND")
		)
		(pad "2" smd rect
			(at -0.94996 0 270)
			(size 0.4318 0.6096)
			(layers "F.Cu" "F.Mask" "F.Paste")
			(net "RST_FW_BIC_PLTRST_C")
		)
		(pad "3" smd rect
			(at -0.94996 0.649986 270)
			(size 0.4318 0.6096)
			(layers "F.Cu" "F.Mask" "F.Paste")
			(net "RST_FW_BIC_PLTRST")
		)
		(pad "4" smd rect
			(at 0.94996 0.649986 270)
			(size 0.4318 0.6096)
			(layers "F.Cu" "F.Mask" "F.Paste")
			(net "GND")
		)
		(pad "5" smd rect
			(at 0.94996 0 270)
			(size 0.4318 0.6096)
			(layers "F.Cu" "F.Mask" "F.Paste")
			(net "RST_FW_BIC_PLTRST_N")
		)
		(pad "6" smd rect
			(at 0.94996 -0.649986 270)
			(size 0.4318 0.6096)
			(layers "F.Cu" "F.Mask" "F.Paste")
			(net "RST_BIC_BUF_RSMRST_N_BUF")
		)
	)
	(footprint ""
		(layer "F.Cu")
		(at 405.003 -383.667 -90)
		(property "Reference" "R6281"
			(at 0 0 270)
			(layer "F.SilkS")
			(hide yes)
			(effects
				(font
					(size 1.27 1.27)
				)
			)
		)
		(property "Value" ""
			(at 0 0 270)
			(layer "F.Fab")
			(effects
				(font
					(size 1.27 1.27)
				)
			)
		)
		(duplicate_pad_numbers_are_jumpers no)
		(fp_line
			(start -0.7874 0.4064)
			(end -0.7874 -0.4064)
			(stroke
				(width 0.1524)
				(type default)
			)
			(layer "F.SilkS")
		)
		(fp_line
			(start 0.7874 0.4064)
			(end -0.7874 0.4064)
			(stroke
				(width 0.1524)
				(type default)
			)
			(layer "F.SilkS")
		)
		(fp_line
			(start -0.7874 -0.4064)
			(end 0.7874 -0.4064)
			(stroke
				(width 0.1524)
				(type default)
			)
			(layer "F.SilkS")
		)
		(fp_line
			(start 0.7874 -0.4064)
			(end 0.7874 0.4064)
			(stroke
				(width 0.1524)
				(type default)
			)
			(layer "F.SilkS")
		)
		(fp_line
			(start -0.67945 0.3048)
			(end -0.67945 -0.305054)
			(stroke
				(width 0.1)
				(type default)
			)
			(layer "F.Fab")
		)
		(fp_line
			(start -0.12065 0.3048)
			(end -0.67945 0.3048)
			(stroke
				(width 0.1)
				(type default)
			)
			(layer "F.Fab")
		)
		(fp_line
			(start 0.120396 0.3048)
			(end 0.120396 0.2794)
			(stroke
				(width 0.1)
				(type default)
			)
			(layer "F.Fab")
		)
		(fp_line
			(start 0.67945 0.3048)
			(end 0.120396 0.3048)
			(stroke
				(width 0.1)
				(type default)
			)
			(layer "F.Fab")
		)
		(fp_line
			(start -0.12065 0.2794)
			(end -0.12065 0.3048)
			(stroke
				(width 0.1)
				(type default)
			)
			(layer "F.Fab")
		)
		(fp_line
			(start 0.120396 0.2794)
			(end -0.12065 0.2794)
			(stroke
				(width 0.1)
				(type default)
			)
			(layer "F.Fab")
		)
		(fp_line
			(start -0.12065 -0.2794)
			(end 0.12065 -0.2794)
			(stroke
				(width 0.1)
				(type default)
			)
			(layer "F.Fab")
		)
		(fp_line
			(start 0.12065 -0.2794)
			(end 0.12065 -0.3048)
			(stroke
				(width 0.1)
				(type default)
			)
			(layer "F.Fab")
		)
		(fp_line
			(start 0.12065 -0.3048)
			(end 0.67945 -0.3048)
			(stroke
				(width 0.1)
				(type default)
			)
			(layer "F.Fab")
		)
		(fp_line
			(start 0.67945 -0.3048)
			(end 0.67945 0.3048)
			(stroke
				(width 0.1)
				(type default)
			)
			(layer "F.Fab")
		)
		(fp_line
			(start -0.67945 -0.305054)
			(end -0.12065 -0.305054)
			(stroke
				(width 0.1)
				(type default)
			)
			(layer "F.Fab")
		)
		(fp_line
			(start -0.12065 -0.305054)
			(end -0.12065 -0.2794)
			(stroke
				(width 0.1)
				(type default)
			)
			(layer "F.Fab")
		)
		(pad "1" smd circle
			(at -0.40005 0 270)
			(size 0 0)
			(layers "F.Cu" "F.Mask" "F.Paste")
			(net "P3V3_AUX")
		)
		(pad "2" smd circle
			(at 0.40005 0 270)
			(size 0 0)
			(layers "F.Cu" "F.Mask" "F.Paste")
			(net "I3C_MB_BMC_R_SCL")
		)
	)
	(footprint ""
		(layer "F.Cu")
		(at 176.210468 -63.652146 180)
		(property "Reference" "R5986"
			(at 0 0 180)
			(layer "F.SilkS")
			(hide yes)
			(effects
				(font
					(size 1.27 1.27)
				)
			)
		)
		(property "Value" ""
			(at 0 0 180)
			(layer "F.Fab")
			(effects
				(font
					(size 1.27 1.27)
				)
			)
		)
		(duplicate_pad_numbers_are_jumpers no)
		(fp_line
			(start 0.7874 0.4064)
			(end -0.7874 0.4064)
			(stroke
				(width 0.1524)
				(type default)
			)
			(layer "F.SilkS")
		)
		(fp_line
			(start 0.7874 -0.4064)
			(end 0.7874 0.4064)
			(stroke
				(width 0.1524)
				(type default)
			)
			(layer "F.SilkS")
		)
		(fp_line
			(start -0.7874 0.4064)
			(end -0.7874 -0.4064)
			(stroke
				(width 0.1524)
				(type default)
			)
			(layer "F.SilkS")
		)
		(fp_line
			(start -0.7874 -0.4064)
			(end 0.7874 -0.4064)
			(stroke
				(width 0.1524)
				(type default)
			)
			(layer "F.SilkS")
		)
		(fp_line
			(start 0.67945 0.3048)
			(end 0.120396 0.3048)
			(stroke
				(width 0.1)
				(type default)
			)
			(layer "F.Fab")
		)
		(fp_line
			(start 0.67945 -0.3048)
			(end 0.67945 0.3048)
			(stroke
				(width 0.1)
				(type default)
			)
			(layer "F.Fab")
		)
		(fp_line
			(start 0.12065 -0.2794)
			(end 0.12065 -0.3048)
			(stroke
				(width 0.1)
				(type default)
			)
			(layer "F.Fab")
		)
		(fp_line
			(start 0.12065 -0.3048)
			(end 0.67945 -0.3048)
			(stroke
				(width 0.1)
				(type default)
			)
			(layer "F.Fab")
		)
		(fp_line
			(start 0.120396 0.3048)
			(end 0.120396 0.2794)
			(stroke
				(width 0.1)
				(type default)
			)
			(layer "F.Fab")
		)
		(fp_line
			(start 0.120396 0.2794)
			(end -0.12065 0.2794)
			(stroke
				(width 0.1)
				(type default)
			)
			(layer "F.Fab")
		)
		(fp_line
			(start -0.12065 0.3048)
			(end -0.67945 0.3048)
			(stroke
				(width 0.1)
				(type default)
			)
			(layer "F.Fab")
		)
		(fp_line
			(start -0.12065 0.2794)
			(end -0.12065 0.3048)
			(stroke
				(width 0.1)
				(type default)
			)
			(layer "F.Fab")
		)
		(fp_line
			(start -0.12065 -0.2794)
			(end 0.12065 -0.2794)
			(stroke
				(width 0.1)
				(type default)
			)
			(layer "F.Fab")
		)
		(fp_line
			(start -0.12065 -0.305054)
			(end -0.12065 -0.2794)
			(stroke
				(width 0.1)
				(type default)
			)
			(layer "F.Fab")
		)
		(fp_line
			(start -0.67945 0.3048)
			(end -0.67945 -0.305054)
			(stroke
				(width 0.1)
				(type default)
			)
			(layer "F.Fab")
		)
		(fp_line
			(start -0.67945 -0.305054)
			(end -0.12065 -0.305054)
			(stroke
				(width 0.1)
				(type default)
			)
			(layer "F.Fab")
		)
		(pad "1" smd circle
			(at -0.40005 0 180)
			(size 0 0)
			(layers "F.Cu" "F.Mask" "F.Paste")
			(net "P5V_AUX")
		)
		(pad "2" smd circle
			(at 0.40005 0 180)
			(size 0 0)
			(layers "F.Cu" "F.Mask" "F.Paste")
			(net "P12V_SSD6_PG_G2")
		)
	)
	(footprint ""
		(layer "F.Cu")
		(at 29.155136 -53.468524 90)
		(property "Reference" "PC509"
			(at 0 0 90)
			(layer "F.SilkS")
			(hide yes)
			(effects
				(font
					(size 1.27 1.27)
				)
			)
		)
		(property "Value" ""
			(at 0 0 90)
			(layer "F.Fab")
			(effects
				(font
					(size 1.27 1.27)
				)
			)
		)
		(duplicate_pad_numbers_are_jumpers no)
		(fp_line
			(start 1.524 -0.762)
			(end 1.524 0.762)
			(stroke
				(width 0.1524)
				(type default)
			)
			(layer "F.SilkS")
		)
		(fp_line
			(start -1.524 -0.762)
			(end 1.524 -0.762)
			(stroke
				(width 0.1524)
				(type default)
			)
			(layer "F.SilkS")
		)
		(fp_line
			(start 1.524 0.762)
			(end -1.524 0.762)
			(stroke
				(width 0.1524)
				(type default)
			)
			(layer "F.SilkS")
		)
		(fp_line
			(start -1.524 0.762)
			(end -1.524 -0.762)
			(stroke
				(width 0.1524)
				(type default)
			)
			(layer "F.SilkS")
		)
		(fp_line
			(start 1.1049 -0.724916)
			(end -1.1049 -0.724916)
			(stroke
				(width 0.1)
				(type default)
			)
			(layer "F.Fab")
		)
		(fp_line
			(start -1.1049 -0.724916)
			(end -1.1049 0.724916)
			(stroke
				(width 0.1)
				(type default)
			)
			(layer "F.Fab")
		)
		(fp_line
			(start 1.1049 0.724916)
			(end 1.1049 -0.724916)
			(stroke
				(width 0.1)
				(type default)
			)
			(layer "F.Fab")
		)
		(fp_line
			(start -1.1049 0.724916)
			(end 1.1049 0.724916)
			(stroke
				(width 0.1)
				(type default)
			)
			(layer "F.Fab")
		)
		(pad "1" smd rect
			(at -0.889 0 270)
			(size 1.016 1.27)
			(layers "F.Cu" "F.Mask" "F.Paste")
			(net "GND")
		)
		(pad "2" smd rect
			(at 0.889 0 270)
			(size 1.016 1.27)
			(layers "F.Cu" "F.Mask" "F.Paste")
			(net "P3V3_AUX")
		)
	)
	(footprint ""
		(layer "F.Cu")
		(at 287.355026 -53.468524 90)
		(property "Reference" "PC545"
			(at 0 0 90)
			(layer "F.SilkS")
			(hide yes)
			(effects
				(font
					(size 1.27 1.27)
				)
			)
		)
		(property "Value" ""
			(at 0 0 90)
			(layer "F.Fab")
			(effects
				(font
					(size 1.27 1.27)
				)
			)
		)
		(duplicate_pad_numbers_are_jumpers no)
		(fp_line
			(start 1.524 -0.762)
			(end 1.524 0.762)
			(stroke
				(width 0.1524)
				(type default)
			)
			(layer "F.SilkS")
		)
		(fp_line
			(start -1.524 -0.762)
			(end 1.524 -0.762)
			(stroke
				(width 0.1524)
				(type default)
			)
			(layer "F.SilkS")
		)
		(fp_line
			(start 1.524 0.762)
			(end -1.524 0.762)
			(stroke
				(width 0.1524)
				(type default)
			)
			(layer "F.SilkS")
		)
		(fp_line
			(start -1.524 0.762)
			(end -1.524 -0.762)
			(stroke
				(width 0.1524)
				(type default)
			)
			(layer "F.SilkS")
		)
		(fp_line
			(start 1.1049 -0.724916)
			(end -1.1049 -0.724916)
			(stroke
				(width 0.1)
				(type default)
			)
			(layer "F.Fab")
		)
		(fp_line
			(start -1.1049 -0.724916)
			(end -1.1049 0.724916)
			(stroke
				(width 0.1)
				(type default)
			)
			(layer "F.Fab")
		)
		(fp_line
			(start 1.1049 0.724916)
			(end 1.1049 -0.724916)
			(stroke
				(width 0.1)
				(type default)
			)
			(layer "F.Fab")
		)
		(fp_line
			(start -1.1049 0.724916)
			(end 1.1049 0.724916)
			(stroke
				(width 0.1)
				(type default)
			)
			(layer "F.Fab")
		)
		(pad "1" smd rect
			(at -0.889 0 270)
			(size 1.016 1.27)
			(layers "F.Cu" "F.Mask" "F.Paste")
			(net "GND")
		)
		(pad "2" smd rect
			(at 0.889 0 270)
			(size 1.016 1.27)
			(layers "F.Cu" "F.Mask" "F.Paste")
			(net "P3V3_AUX")
		)
	)
	(footprint ""
		(layer "F.Cu")
		(at 112.198404 -164.52342)
		(property "Reference" "PC29"
			(at 0 0 0)
			(layer "F.SilkS")
			(hide yes)
			(effects
				(font
					(size 1.27 1.27)
				)
			)
		)
		(property "Value" ""
			(at 0 0 0)
			(layer "F.Fab")
			(effects
				(font
					(size 1.27 1.27)
				)
			)
		)
		(duplicate_pad_numbers_are_jumpers no)
		(fp_line
			(start -1.524 -0.762)
			(end 1.524 -0.762)
			(stroke
				(width 0.1524)
				(type default)
			)
			(layer "F.SilkS")
		)
		(fp_line
			(start -1.524 0.762)
			(end -1.524 -0.762)
			(stroke
				(width 0.1524)
				(type default)
			)
			(layer "F.SilkS")
		)
		(fp_line
			(start 1.524 -0.762)
			(end 1.524 0.762)
			(stroke
				(width 0.1524)
				(type default)
			)
			(layer "F.SilkS")
		)
		(fp_line
			(start 1.524 0.762)
			(end -1.524 0.762)
			(stroke
				(width 0.1524)
				(type default)
			)
			(layer "F.SilkS")
		)
		(fp_line
			(start -1.1049 -0.724916)
			(end -1.1049 0.724916)
			(stroke
				(width 0.1)
				(type default)
			)
			(layer "F.Fab")
		)
		(fp_line
			(start -1.1049 0.724916)
			(end 1.1049 0.724916)
			(stroke
				(width 0.1)
				(type default)
			)
			(layer "F.Fab")
		)
		(fp_line
			(start 1.1049 -0.724916)
			(end -1.1049 -0.724916)
			(stroke
				(width 0.1)
				(type default)
			)
			(layer "F.Fab")
		)
		(fp_line
			(start 1.1049 0.724916)
			(end 1.1049 -0.724916)
			(stroke
				(width 0.1)
				(type default)
			)
			(layer "F.Fab")
		)
		(pad "1" smd rect
			(at -0.889 0 180)
			(size 1.016 1.27)
			(layers "F.Cu" "F.Mask" "F.Paste")
			(net "SW_P12V_P3V3_AUX_FLT")
		)
		(pad "2" smd rect
			(at 0.889 0 180)
			(size 1.016 1.27)
			(layers "F.Cu" "F.Mask" "F.Paste")
			(net "GND")
		)
	)
	(footprint ""
		(layer "F.Cu")
		(at 238.385604 -185.17235 -90)
		(property "Reference" "C3645"
			(at 0 0 270)
			(layer "F.SilkS")
			(hide yes)
			(effects
				(font
					(size 1.27 1.27)
				)
			)
		)
		(property "Value" ""
			(at 0 0 270)
			(layer "F.Fab")
			(effects
				(font
					(size 1.27 1.27)
				)
			)
		)
		(duplicate_pad_numbers_are_jumpers no)
		(fp_line
			(start -0.7874 0.4064)
			(end -0.7874 -0.4064)
			(stroke
				(width 0.1524)
				(type default)
			)
			(layer "F.SilkS")
		)
		(fp_line
			(start 0.7874 0.4064)
			(end -0.7874 0.4064)
			(stroke
				(width 0.1524)
				(type default)
			)
			(layer "F.SilkS")
		)
		(fp_line
			(start -0.7874 -0.4064)
			(end 0.7874 -0.4064)
			(stroke
				(width 0.1524)
				(type default)
			)
			(layer "F.SilkS")
		)
		(fp_line
			(start 0.7874 -0.4064)
			(end 0.7874 0.4064)
			(stroke
				(width 0.1524)
				(type default)
			)
			(layer "F.SilkS")
		)
		(fp_line
			(start -0.67945 0.3048)
			(end -0.67945 -0.305054)
			(stroke
				(width 0.1)
				(type default)
			)
			(layer "F.Fab")
		)
		(fp_line
			(start -0.12065 0.3048)
			(end -0.67945 0.3048)
			(stroke
				(width 0.1)
				(type default)
			)
			(layer "F.Fab")
		)
		(fp_line
			(start 0.120396 0.3048)
			(end 0.120396 0.2794)
			(stroke
				(width 0.1)
				(type default)
			)
			(layer "F.Fab")
		)
		(fp_line
			(start 0.67945 0.3048)
			(end 0.120396 0.3048)
			(stroke
				(width 0.1)
				(type default)
			)
			(layer "F.Fab")
		)
		(fp_line
			(start -0.12065 0.2794)
			(end -0.12065 0.3048)
			(stroke
				(width 0.1)
				(type default)
			)
			(layer "F.Fab")
		)
		(fp_line
			(start 0.120396 0.2794)
			(end -0.12065 0.2794)
			(stroke
				(width 0.1)
				(type default)
			)
			(layer "F.Fab")
		)
		(fp_line
			(start -0.12065 -0.2794)
			(end 0.12065 -0.2794)
			(stroke
				(width 0.1)
				(type default)
			)
			(layer "F.Fab")
		)
		(fp_line
			(start 0.12065 -0.2794)
			(end 0.12065 -0.3048)
			(stroke
				(width 0.1)
				(type default)
			)
			(layer "F.Fab")
		)
		(fp_line
			(start 0.12065 -0.3048)
			(end 0.67945 -0.3048)
			(stroke
				(width 0.1)
				(type default)
			)
			(layer "F.Fab")
		)
		(fp_line
			(start 0.67945 -0.3048)
			(end 0.67945 0.3048)
			(stroke
				(width 0.1)
				(type default)
			)
			(layer "F.Fab")
		)
		(fp_line
			(start -0.67945 -0.305054)
			(end -0.12065 -0.305054)
			(stroke
				(width 0.1)
				(type default)
			)
			(layer "F.Fab")
		)
		(fp_line
			(start -0.12065 -0.305054)
			(end -0.12065 -0.2794)
			(stroke
				(width 0.1)
				(type default)
			)
			(layer "F.Fab")
		)
		(pad "1" smd circle
			(at -0.40005 0 270)
			(size 0 0)
			(layers "F.Cu" "F.Mask" "F.Paste")
			(net "GND")
		)
		(pad "2" smd circle
			(at 0.40005 0 270)
			(size 0 0)
			(layers "F.Cu" "F.Mask" "F.Paste")
			(net "P3V3_AUX")
		)
	)
)
